(kicad_pcb
	(version 20260206)
	(generator "pcbnew")
	(generator_version "10.0")
	(general
		(thickness 1.6)
		(legacy_teardrops no)
	)
	(paper "A4")
	(title_block
		(title "15969-1a.1015WZS0858.brd")
		(comment 1 "Tioga Pass / footprint 93 of 295 (SLOT2), pads 1-75 of 166")
	)
	(layers
		(0 "F.Cu" signal "TOP")
		(4 "In1.Cu" signal "L2GND")
		(6 "In2.Cu" signal "L3")
		(8 "In3.Cu" signal "L4")
		(10 "In4.Cu" signal "L5GND")
		(2 "B.Cu" signal "BOTTOM")
		(9 "F.Adhes" user "F.Adhesive")
		(11 "B.Adhes" user "B.Adhesive")
		(13 "F.Paste" user "Package Geometry/Pastemask Top")
		(15 "B.Paste" user "Package Geometry/Pastemask Bottom")
		(5 "F.SilkS" user "Ref Des/Silkscreen Top")
		(7 "B.SilkS" user "Ref Des/Silkscreen Bottom")
		(1 "F.Mask" user "Board Geometry/Soldermask Top")
		(3 "B.Mask" user "Board Geometry/Soldermask Bottom")
		(17 "Dwgs.User" user "User.Drawings")
		(19 "Cmts.User" user "User.Comments")
		(21 "Eco1.User" user "User.Eco1")
		(23 "Eco2.User" user "User.Eco2")
		(25 "Edge.Cuts" user "Board Geometry/Outline")
		(27 "Margin" user)
		(31 "F.CrtYd" user "Package Geometry/Place Bound Top")
		(29 "B.CrtYd" user "Package Geometry/Place Bound Bottom")
		(35 "F.Fab" user "Ref Des/Assembly Top")
		(33 "B.Fab" user "Ref Des/Assembly Bottom")
	)
	(footprint ""
		(layer "F.Cu")
		(at 42.729912 -10.500106)
		(property "Reference" "SLOT2"
			(at 0 0 0)
			(layer "F.SilkS")
			(hide yes)
			(effects
				(font
					(size 1.27 1.27)
				)
			)
		)
		(property "Value" "PCISLT164-129-GP"
			(at -15.9639 4.8514 0)
			(unlocked yes)
			(layer "F.Fab")
			(hide yes)
			(effects
				(font
					(size 1.016 1.016)
					(thickness 0.1524)
				)
			)
		)
		(property "Device Type" "10018783-10203TLF"
			(at -15.9639 3.3274 0)
			(unlocked yes)
			(layer "F.Fab")
			(hide yes)
			(effects
				(font
					(size 1.016 1.016)
					(thickness 0.1524)
				)
			)
		)
		(duplicate_pad_numbers_are_jumpers no)
		(pad "" np_thru_hole circle
			(at 0 0)
			(size 0.254 0.254)
			(drill 2.3622)
			(layers "*.Cu" "*.Mask")
			(clearance 1.4097)
			(thermal_gap 1.4097)
		)
		(pad "" np_thru_hole circle
			(at 73.14946 0)
			(size 0.254 0.254)
			(drill 2.3622)
			(layers "*.Cu" "*.Mask")
			(clearance 1.4097)
			(thermal_gap 1.4097)
		)
		(pad "A1" thru_hole circle
			(at -11.64971 -1.24968)
			(size 1.0668 1.0668)
			(drill 0.7112)
			(layers "*.Cu" "*.Mask")
			(remove_unused_layers no)
			(net "PD_SLOT2_PRSNT1")
			(clearance 0.1778)
			(thermal_gap 0.1778)
		)
		(pad "A2" thru_hole circle
			(at -10.65022 -3.24993)
			(size 1.0668 1.0668)
			(drill 0.7112)
			(layers "*.Cu" "*.Mask")
			(remove_unused_layers no)
			(net "P12V_SLOT2")
			(clearance 0.1778)
			(thermal_gap 0.1778)
		)
		(pad "A3" thru_hole circle
			(at -9.64946 -1.24968)
			(size 1.0668 1.0668)
			(drill 0.7112)
			(layers "*.Cu" "*.Mask")
			(remove_unused_layers no)
			(net "P12V_SLOT2")
			(clearance 0.1778)
			(thermal_gap 0.1778)
		)
		(pad "A4" thru_hole circle
			(at -8.64997 -3.24993)
			(size 1.0668 1.0668)
			(drill 0.7112)
			(layers "*.Cu" "*.Mask")
			(remove_unused_layers no)
			(net "GND")
			(clearance 0.1778)
			(thermal_gap 0.1778)
		)
		(pad "A5" thru_hole circle
			(at -7.65048 -1.24968)
			(size 1.0668 1.0668)
			(drill 0.7112)
			(layers "*.Cu" "*.Mask")
			(remove_unused_layers no)
			(net "Net_102")
			(clearance 0.1778)
			(thermal_gap 0.1778)
		)
		(pad "A6" thru_hole circle
			(at -6.64972 -3.24993)
			(size 1.0668 1.0668)
			(drill 0.7112)
			(layers "*.Cu" "*.Mask")
			(remove_unused_layers no)
			(net "Net_103")
			(clearance 0.1778)
			(thermal_gap 0.1778)
		)
		(pad "A7" thru_hole circle
			(at -5.65023 -1.24968)
			(size 1.0668 1.0668)
			(drill 0.7112)
			(layers "*.Cu" "*.Mask")
			(remove_unused_layers no)
			(net "SMCLK_PCH_SLOT2_R")
			(clearance 0.1778)
			(thermal_gap 0.1778)
		)
		(pad "A8" thru_hole circle
			(at -4.64947 -3.24993)
			(size 1.0668 1.0668)
			(drill 0.7112)
			(layers "*.Cu" "*.Mask")
			(remove_unused_layers no)
			(net "SMDAT_PCH_SLOT2_R")
			(clearance 0.1778)
			(thermal_gap 0.1778)
		)
		(pad "A9" thru_hole circle
			(at -3.64998 -1.24968)
			(size 1.0668 1.0668)
			(drill 0.7112)
			(layers "*.Cu" "*.Mask")
			(remove_unused_layers no)
			(net "P3V3")
			(clearance 0.1778)
			(thermal_gap 0.1778)
		)
		(pad "A10" thru_hole circle
			(at -2.65049 -3.24993)
			(size 1.0668 1.0668)
			(drill 0.7112)
			(layers "*.Cu" "*.Mask")
			(remove_unused_layers no)
			(net "P3V3")
			(clearance 0.1778)
			(thermal_gap 0.1778)
		)
		(pad "A11" thru_hole circle
			(at -1.64973 -1.24968)
			(size 1.0668 1.0668)
			(drill 0.7112)
			(layers "*.Cu" "*.Mask")
			(remove_unused_layers no)
			(net "RESET_BUF_N_SLOT2")
			(clearance 0.1778)
			(thermal_gap 0.1778)
		)
		(pad "A12" thru_hole circle
			(at 1.35001 -3.24993)
			(size 1.0668 1.0668)
			(drill 0.7112)
			(layers "*.Cu" "*.Mask")
			(remove_unused_layers no)
			(net "GND")
			(clearance 0.1778)
			(thermal_gap 0.1778)
		)
		(pad "A13" thru_hole circle
			(at 2.3495 -1.24968)
			(size 1.0668 1.0668)
			(drill 0.7112)
			(layers "*.Cu" "*.Mask")
			(remove_unused_layers no)
			(net "CLK_100M_PCH_SLOTX24_S5_DP")
			(clearance 0.1778)
			(thermal_gap 0.1778)
		)
		(pad "A14" thru_hole circle
			(at 3.35026 -3.24993)
			(size 1.0668 1.0668)
			(drill 0.7112)
			(layers "*.Cu" "*.Mask")
			(remove_unused_layers no)
			(net "CLK_100M_PCH_SLOTX24_S5_DN")
			(clearance 0.1778)
			(thermal_gap 0.1778)
		)
		(pad "A15" thru_hole circle
			(at 4.34975 -1.24968)
			(size 1.0668 1.0668)
			(drill 0.7112)
			(layers "*.Cu" "*.Mask")
			(remove_unused_layers no)
			(net "GND")
			(clearance 0.1778)
			(thermal_gap 0.1778)
		)
		(pad "A16" thru_hole circle
			(at 5.35051 -3.24993)
			(size 1.0668 1.0668)
			(drill 0.7112)
			(layers "*.Cu" "*.Mask")
			(remove_unused_layers no)
			(net "P3E_CPU0_PE1_PCH_CON_RXP<15>")
			(clearance 0.1778)
			(thermal_gap 0.1778)
		)
		(pad "A17" thru_hole circle
			(at 6.35 -1.24968)
			(size 1.0668 1.0668)
			(drill 0.7112)
			(layers "*.Cu" "*.Mask")
			(remove_unused_layers no)
			(net "P3E_CPU0_PE1_PCH_CON_RXN<15>")
			(clearance 0.1778)
			(thermal_gap 0.1778)
		)
		(pad "A18" thru_hole circle
			(at 7.34949 -3.24993)
			(size 1.0668 1.0668)
			(drill 0.7112)
			(layers "*.Cu" "*.Mask")
			(remove_unused_layers no)
			(net "GND")
			(clearance 0.1778)
			(thermal_gap 0.1778)
		)
		(pad "A19" thru_hole circle
			(at 8.35025 -1.24968)
			(size 1.0668 1.0668)
			(drill 0.7112)
			(layers "*.Cu" "*.Mask")
			(remove_unused_layers no)
			(net "Net_99")
			(clearance 0.1778)
			(thermal_gap 0.1778)
		)
		(pad "A20" thru_hole circle
			(at 9.34974 -3.24993)
			(size 1.0668 1.0668)
			(drill 0.7112)
			(layers "*.Cu" "*.Mask")
			(remove_unused_layers no)
			(net "GND")
			(clearance 0.1778)
			(thermal_gap 0.1778)
		)
		(pad "A21" thru_hole circle
			(at 10.3505 -1.24968)
			(size 1.0668 1.0668)
			(drill 0.7112)
			(layers "*.Cu" "*.Mask")
			(remove_unused_layers no)
			(net "P3E_CPU0_PE1_PCH_CON_RXP<14>")
			(clearance 0.1778)
			(thermal_gap 0.1778)
		)
		(pad "A22" thru_hole circle
			(at 11.34999 -3.24993)
			(size 1.0668 1.0668)
			(drill 0.7112)
			(layers "*.Cu" "*.Mask")
			(remove_unused_layers no)
			(net "P3E_CPU0_PE1_PCH_CON_RXN<14>")
			(clearance 0.1778)
			(thermal_gap 0.1778)
		)
		(pad "A23" thru_hole circle
			(at 12.34948 -1.24968)
			(size 1.0668 1.0668)
			(drill 0.7112)
			(layers "*.Cu" "*.Mask")
			(remove_unused_layers no)
			(net "GND")
			(clearance 0.1778)
			(thermal_gap 0.1778)
		)
		(pad "A24" thru_hole circle
			(at 13.35024 -3.24993)
			(size 1.0668 1.0668)
			(drill 0.7112)
			(layers "*.Cu" "*.Mask")
			(remove_unused_layers no)
			(net "GND")
			(clearance 0.1778)
			(thermal_gap 0.1778)
		)
		(pad "A25" thru_hole circle
			(at 14.34973 -1.24968)
			(size 1.0668 1.0668)
			(drill 0.7112)
			(layers "*.Cu" "*.Mask")
			(remove_unused_layers no)
			(net "P3E_CPU0_PE1_PCH_CON_RXP<13>")
			(clearance 0.1778)
			(thermal_gap 0.1778)
		)
		(pad "A26" thru_hole circle
			(at 15.35049 -3.24993)
			(size 1.0668 1.0668)
			(drill 0.7112)
			(layers "*.Cu" "*.Mask")
			(remove_unused_layers no)
			(net "P3E_CPU0_PE1_PCH_CON_RXN<13>")
			(clearance 0.1778)
			(thermal_gap 0.1778)
		)
		(pad "A27" thru_hole circle
			(at 16.34998 -1.24968)
			(size 1.0668 1.0668)
			(drill 0.7112)
			(layers "*.Cu" "*.Mask")
			(remove_unused_layers no)
			(net "GND")
			(clearance 0.1778)
			(thermal_gap 0.1778)
		)
		(pad "A28" thru_hole circle
			(at 17.34947 -3.24993)
			(size 1.0668 1.0668)
			(drill 0.7112)
			(layers "*.Cu" "*.Mask")
			(remove_unused_layers no)
			(net "GND")
			(clearance 0.1778)
			(thermal_gap 0.1778)
		)
		(pad "A29" thru_hole circle
			(at 18.35023 -1.24968)
			(size 1.0668 1.0668)
			(drill 0.7112)
			(layers "*.Cu" "*.Mask")
			(remove_unused_layers no)
			(net "P3E_CPU0_PE1_PCH_CON_RXP<12>")
			(clearance 0.1778)
			(thermal_gap 0.1778)
		)
		(pad "A30" thru_hole circle
			(at 19.34972 -3.24993)
			(size 1.0668 1.0668)
			(drill 0.7112)
			(layers "*.Cu" "*.Mask")
			(remove_unused_layers no)
			(net "P3E_CPU0_PE1_PCH_CON_RXN<12>")
			(clearance 0.1778)
			(thermal_gap 0.1778)
		)
		(pad "A31" thru_hole circle
			(at 20.35048 -1.24968)
			(size 1.0668 1.0668)
			(drill 0.7112)
			(layers "*.Cu" "*.Mask")
			(remove_unused_layers no)
			(net "GND")
			(clearance 0.1778)
			(thermal_gap 0.1778)
		)
		(pad "A32" thru_hole circle
			(at 21.34997 -3.24993)
			(size 1.0668 1.0668)
			(drill 0.7112)
			(layers "*.Cu" "*.Mask")
			(remove_unused_layers no)
			(net "USB_HUB_PCIE_DP0")
			(clearance 0.1778)
			(thermal_gap 0.1778)
		)
		(pad "A33" thru_hole circle
			(at 22.34946 -1.24968)
			(size 1.0668 1.0668)
			(drill 0.7112)
			(layers "*.Cu" "*.Mask")
			(remove_unused_layers no)
			(net "USB_HUB_PCIE_DN0")
			(clearance 0.1778)
			(thermal_gap 0.1778)
		)
		(pad "A34" thru_hole circle
			(at 23.35022 -3.24993)
			(size 1.0668 1.0668)
			(drill 0.7112)
			(layers "*.Cu" "*.Mask")
			(remove_unused_layers no)
			(net "GND")
			(clearance 0.1778)
			(thermal_gap 0.1778)
		)
		(pad "A35" thru_hole circle
			(at 24.34971 -1.24968)
			(size 1.0668 1.0668)
			(drill 0.7112)
			(layers "*.Cu" "*.Mask")
			(remove_unused_layers no)
			(net "P3E_CPU0_PE1_PCH_CON_RXP<11>")
			(clearance 0.1778)
			(thermal_gap 0.1778)
		)
		(pad "A36" thru_hole circle
			(at 25.35047 -3.24993)
			(size 1.0668 1.0668)
			(drill 0.7112)
			(layers "*.Cu" "*.Mask")
			(remove_unused_layers no)
			(net "P3E_CPU0_PE1_PCH_CON_RXN<11>")
			(clearance 0.1778)
			(thermal_gap 0.1778)
		)
		(pad "A37" thru_hole circle
			(at 26.34996 -1.24968)
			(size 1.0668 1.0668)
			(drill 0.7112)
			(layers "*.Cu" "*.Mask")
			(remove_unused_layers no)
			(net "GND")
			(clearance 0.1778)
			(thermal_gap 0.1778)
		)
		(pad "A38" thru_hole circle
			(at 27.34945 -3.24993)
			(size 1.0668 1.0668)
			(drill 0.7112)
			(layers "*.Cu" "*.Mask")
			(remove_unused_layers no)
			(net "GND")
			(clearance 0.1778)
			(thermal_gap 0.1778)
		)
		(pad "A39" thru_hole circle
			(at 28.35021 -1.24968)
			(size 1.0668 1.0668)
			(drill 0.7112)
			(layers "*.Cu" "*.Mask")
			(remove_unused_layers no)
			(net "P3E_CPU0_PE1_PCH_CON_RXP<10>")
			(clearance 0.1778)
			(thermal_gap 0.1778)
		)
		(pad "A40" thru_hole circle
			(at 29.3497 -3.24993)
			(size 1.0668 1.0668)
			(drill 0.7112)
			(layers "*.Cu" "*.Mask")
			(remove_unused_layers no)
			(net "P3E_CPU0_PE1_PCH_CON_RXN<10>")
			(clearance 0.1778)
			(thermal_gap 0.1778)
		)
		(pad "A41" thru_hole circle
			(at 30.35046 -1.24968)
			(size 1.0668 1.0668)
			(drill 0.7112)
			(layers "*.Cu" "*.Mask")
			(remove_unused_layers no)
			(net "GND")
			(clearance 0.1778)
			(thermal_gap 0.1778)
		)
		(pad "A42" thru_hole circle
			(at 31.34995 -3.24993)
			(size 1.0668 1.0668)
			(drill 0.7112)
			(layers "*.Cu" "*.Mask")
			(remove_unused_layers no)
			(net "GND")
			(clearance 0.1778)
			(thermal_gap 0.1778)
		)
		(pad "A43" thru_hole circle
			(at 32.34944 -1.24968)
			(size 1.0668 1.0668)
			(drill 0.7112)
			(layers "*.Cu" "*.Mask")
			(remove_unused_layers no)
			(net "P3E_CPU0_PE1_PCH_CON_RXP<9>")
			(clearance 0.1778)
			(thermal_gap 0.1778)
		)
		(pad "A44" thru_hole circle
			(at 33.3502 -3.24993)
			(size 1.0668 1.0668)
			(drill 0.7112)
			(layers "*.Cu" "*.Mask")
			(remove_unused_layers no)
			(net "P3E_CPU0_PE1_PCH_CON_RXN<9>")
			(clearance 0.1778)
			(thermal_gap 0.1778)
		)
		(pad "A45" thru_hole circle
			(at 34.34969 -1.24968)
			(size 1.0668 1.0668)
			(drill 0.7112)
			(layers "*.Cu" "*.Mask")
			(remove_unused_layers no)
			(net "GND")
			(clearance 0.1778)
			(thermal_gap 0.1778)
		)
		(pad "A46" thru_hole circle
			(at 35.35045 -3.24993)
			(size 1.0668 1.0668)
			(drill 0.7112)
			(layers "*.Cu" "*.Mask")
			(remove_unused_layers no)
			(net "GND")
			(clearance 0.1778)
			(thermal_gap 0.1778)
		)
		(pad "A47" thru_hole circle
			(at 36.34994 -1.24968)
			(size 1.0668 1.0668)
			(drill 0.7112)
			(layers "*.Cu" "*.Mask")
			(remove_unused_layers no)
			(net "P3E_CPU0_PE1_PCH_CON_RXP<8>")
			(clearance 0.1778)
			(thermal_gap 0.1778)
		)
		(pad "A48" thru_hole circle
			(at 37.34943 -3.24993)
			(size 1.0668 1.0668)
			(drill 0.7112)
			(layers "*.Cu" "*.Mask")
			(remove_unused_layers no)
			(net "P3E_CPU0_PE1_PCH_CON_RXN<8>")
			(clearance 0.1778)
			(thermal_gap 0.1778)
		)
		(pad "A49" thru_hole circle
			(at 38.35019 -1.24968)
			(size 1.0668 1.0668)
			(drill 0.7112)
			(layers "*.Cu" "*.Mask")
			(remove_unused_layers no)
			(net "GND")
			(clearance 0.1778)
			(thermal_gap 0.1778)
		)
		(pad "A50" thru_hole circle
			(at 39.34968 -3.24993)
			(size 1.0668 1.0668)
			(drill 0.7112)
			(layers "*.Cu" "*.Mask")
			(remove_unused_layers no)
			(net "Net_98")
			(clearance 0.1778)
			(thermal_gap 0.1778)
		)
		(pad "A51" thru_hole circle
			(at 40.35044 -1.24968)
			(size 1.0668 1.0668)
			(drill 0.7112)
			(layers "*.Cu" "*.Mask")
			(remove_unused_layers no)
			(net "GND")
			(clearance 0.1778)
			(thermal_gap 0.1778)
		)
		(pad "A52" thru_hole circle
			(at 41.34993 -3.24993)
			(size 1.0668 1.0668)
			(drill 0.7112)
			(layers "*.Cu" "*.Mask")
			(remove_unused_layers no)
			(net "P3E_CPU0_PE1_SS_C_RXP<7>")
			(clearance 0.1778)
			(thermal_gap 0.1778)
		)
		(pad "A53" thru_hole circle
			(at 42.34942 -1.24968)
			(size 1.0668 1.0668)
			(drill 0.7112)
			(layers "*.Cu" "*.Mask")
			(remove_unused_layers no)
			(net "P3E_CPU0_PE1_SS_C_RXN<7>")
			(clearance 0.1778)
			(thermal_gap 0.1778)
		)
		(pad "A54" thru_hole circle
			(at 43.35018 -3.24993)
			(size 1.0668 1.0668)
			(drill 0.7112)
			(layers "*.Cu" "*.Mask")
			(remove_unused_layers no)
			(net "GND")
			(clearance 0.1778)
			(thermal_gap 0.1778)
		)
		(pad "A55" thru_hole circle
			(at 44.34967 -1.24968)
			(size 1.0668 1.0668)
			(drill 0.7112)
			(layers "*.Cu" "*.Mask")
			(remove_unused_layers no)
			(net "GND")
			(clearance 0.1778)
			(thermal_gap 0.1778)
		)
		(pad "A56" thru_hole circle
			(at 45.35043 -3.24993)
			(size 1.0668 1.0668)
			(drill 0.7112)
			(layers "*.Cu" "*.Mask")
			(remove_unused_layers no)
			(net "P3E_CPU0_PE1_SS_C_RXP<6>")
			(clearance 0.1778)
			(thermal_gap 0.1778)
		)
		(pad "A57" thru_hole circle
			(at 46.34992 -1.24968)
			(size 1.0668 1.0668)
			(drill 0.7112)
			(layers "*.Cu" "*.Mask")
			(remove_unused_layers no)
			(net "P3E_CPU0_PE1_SS_C_RXN<6>")
			(clearance 0.1778)
			(thermal_gap 0.1778)
		)
		(pad "A58" thru_hole circle
			(at 47.34941 -3.24993)
			(size 1.0668 1.0668)
			(drill 0.7112)
			(layers "*.Cu" "*.Mask")
			(remove_unused_layers no)
			(net "GND")
			(clearance 0.1778)
			(thermal_gap 0.1778)
		)
		(pad "A59" thru_hole circle
			(at 48.35017 -1.24968)
			(size 1.0668 1.0668)
			(drill 0.7112)
			(layers "*.Cu" "*.Mask")
			(remove_unused_layers no)
			(net "GND")
			(clearance 0.1778)
			(thermal_gap 0.1778)
		)
		(pad "A60" thru_hole circle
			(at 49.34966 -3.24993)
			(size 1.0668 1.0668)
			(drill 0.7112)
			(layers "*.Cu" "*.Mask")
			(remove_unused_layers no)
			(net "P3E_CPU0_PE1_SS_C_RXP<5>")
			(clearance 0.1778)
			(thermal_gap 0.1778)
		)
		(pad "A61" thru_hole circle
			(at 50.35042 -1.24968)
			(size 1.0668 1.0668)
			(drill 0.7112)
			(layers "*.Cu" "*.Mask")
			(remove_unused_layers no)
			(net "P3E_CPU0_PE1_SS_C_RXN<5>")
			(clearance 0.1778)
			(thermal_gap 0.1778)
		)
		(pad "A62" thru_hole circle
			(at 51.34991 -3.24993)
			(size 1.0668 1.0668)
			(drill 0.7112)
			(layers "*.Cu" "*.Mask")
			(remove_unused_layers no)
			(net "GND")
			(clearance 0.1778)
			(thermal_gap 0.1778)
		)
		(pad "A63" thru_hole circle
			(at 52.3494 -1.24968)
			(size 1.0668 1.0668)
			(drill 0.7112)
			(layers "*.Cu" "*.Mask")
			(remove_unused_layers no)
			(net "GND")
			(clearance 0.1778)
			(thermal_gap 0.1778)
		)
		(pad "A64" thru_hole circle
			(at 53.35016 -3.24993)
			(size 1.0668 1.0668)
			(drill 0.7112)
			(layers "*.Cu" "*.Mask")
			(remove_unused_layers no)
			(net "P3E_CPU0_PE1_SS_C_RXP<4>")
			(clearance 0.1778)
			(thermal_gap 0.1778)
		)
		(pad "A65" thru_hole circle
			(at 54.34965 -1.24968)
			(size 1.0668 1.0668)
			(drill 0.7112)
			(layers "*.Cu" "*.Mask")
			(remove_unused_layers no)
			(net "P3E_CPU0_PE1_SS_C_RXN<4>")
			(clearance 0.1778)
			(thermal_gap 0.1778)
		)
		(pad "A66" thru_hole circle
			(at 55.35041 -3.24993)
			(size 1.0668 1.0668)
			(drill 0.7112)
			(layers "*.Cu" "*.Mask")
			(remove_unused_layers no)
			(net "GND")
			(clearance 0.1778)
			(thermal_gap 0.1778)
		)
		(pad "A67" thru_hole circle
			(at 56.3499 -1.24968)
			(size 1.0668 1.0668)
			(drill 0.7112)
			(layers "*.Cu" "*.Mask")
			(remove_unused_layers no)
			(net "GND")
			(clearance 0.1778)
			(thermal_gap 0.1778)
		)
		(pad "A68" thru_hole circle
			(at 57.34939 -3.24993)
			(size 1.0668 1.0668)
			(drill 0.7112)
			(layers "*.Cu" "*.Mask")
			(remove_unused_layers no)
			(net "P3E_CPU0_PE1_SS_C_RXP<3>")
			(clearance 0.1778)
			(thermal_gap 0.1778)
		)
		(pad "A69" thru_hole circle
			(at 58.35015 -1.24968)
			(size 1.0668 1.0668)
			(drill 0.7112)
			(layers "*.Cu" "*.Mask")
			(remove_unused_layers no)
			(net "P3E_CPU0_PE1_SS_C_RXN<3>")
			(clearance 0.1778)
			(thermal_gap 0.1778)
		)
		(pad "A70" thru_hole circle
			(at 59.34964 -3.24993)
			(size 1.0668 1.0668)
			(drill 0.7112)
			(layers "*.Cu" "*.Mask")
			(remove_unused_layers no)
			(net "GND")
			(clearance 0.1778)
			(thermal_gap 0.1778)
		)
		(pad "A71" thru_hole circle
			(at 60.3504 -1.24968)
			(size 1.0668 1.0668)
			(drill 0.7112)
			(layers "*.Cu" "*.Mask")
			(remove_unused_layers no)
			(net "GND")
			(clearance 0.1778)
			(thermal_gap 0.1778)
		)
		(pad "A72" thru_hole circle
			(at 61.34989 -3.24993)
			(size 1.0668 1.0668)
			(drill 0.7112)
			(layers "*.Cu" "*.Mask")
			(remove_unused_layers no)
			(net "P3E_CPU0_PE1_SS_C_RXP<2>")
			(clearance 0.1778)
			(thermal_gap 0.1778)
		)
		(pad "A73" thru_hole circle
			(at 62.34938 -1.24968)
			(size 1.0668 1.0668)
			(drill 0.7112)
			(layers "*.Cu" "*.Mask")
			(remove_unused_layers no)
			(net "P3E_CPU0_PE1_SS_C_RXN<2>")
			(clearance 0.1778)
			(thermal_gap 0.1778)
		)
	)
)
